(kicad_pcb
	(version 20260206)
	(generator "pcbnew")
	(generator_version "10.0")
	(general
		(thickness 1.6)
		(legacy_teardrops no)
	)
	(paper "A4")
	(title_block
		(title "04192023_DAF0TMB3IC0_F0TG_MB_C_brd_V02_OCP.brd")
		(comment 1 "Grand Teton / footprints 3552-3558 of 8354")
	)
	(layers
		(0 "F.Cu" signal "TOP")
		(4 "In1.Cu" signal "GND")
		(6 "In2.Cu" signal "IN1")
		(8 "In3.Cu" signal "GND1")
		(10 "In4.Cu" signal "IN2")
		(12 "In5.Cu" signal "GND2")
		(14 "In6.Cu" signal "IN3")
		(16 "In7.Cu" signal "GND3")
		(18 "In8.Cu" signal "VCC")
		(20 "In9.Cu" signal "VCC1")
		(22 "In10.Cu" signal "GND4")
		(24 "In11.Cu" signal "IN4")
		(26 "In12.Cu" signal "GND5")
		(28 "In13.Cu" signal "IN5")
		(30 "In14.Cu" signal "GND6")
		(32 "In15.Cu" signal "IN6")
		(34 "In16.Cu" signal "GND7")
		(2 "B.Cu" signal "BOTTOM")
		(9 "F.Adhes" user "F.Adhesive")
		(11 "B.Adhes" user "B.Adhesive")
		(13 "F.Paste" user "Package Geometry/Pastemask Top")
		(15 "B.Paste" user "Package Geometry/Pastemask Bottom")
		(5 "F.SilkS" user "Ref Des/Silkscreen Top")
		(7 "B.SilkS" user "Ref Des/Silkscreen Bottom")
		(1 "F.Mask" user "Board Geometry/Soldermask Top")
		(3 "B.Mask" user "Board Geometry/Soldermask Bottom")
		(17 "Dwgs.User" user "User.Drawings")
		(19 "Cmts.User" user "User.Comments")
		(21 "Eco1.User" user "User.Eco1")
		(23 "Eco2.User" user "User.Eco2")
		(25 "Edge.Cuts" user "Board Geometry/Outline")
		(27 "Margin" user)
		(31 "F.CrtYd" user "Package Geometry/Place Bound Top")
		(29 "B.CrtYd" user "Package Geometry/Place Bound Bottom")
		(35 "F.Fab" user "Ref Des/Assembly Top")
		(33 "B.Fab" user "Ref Des/Assembly Bottom")
	)
	(footprint ""
		(layer "F.Cu")
		(at 73.843134 -186.942984 180)
		(property "Reference" "PL33"
			(at 4.778756 2.166366 90)
			(unlocked yes)
			(layer "F.SilkS")
			(effects
				(font
					(size 0.7874 0.5842)
					(thickness 0.1524)
				)
				(justify left)
			)
		)
		(property "Value" ""
			(at 0 0 180)
			(layer "F.Fab")
			(effects
				(font
					(size 1.27 1.27)
				)
			)
		)
		(duplicate_pad_numbers_are_jumpers no)
		(fp_line
			(start 3.750056 5.500116)
			(end 3.750056 -5.500116)
			(stroke
				(width 0.1524)
				(type default)
			)
			(layer "F.SilkS")
		)
		(fp_line
			(start 3.750056 -5.500116)
			(end 2.393442 -5.500116)
			(stroke
				(width 0.1524)
				(type default)
			)
			(layer "F.SilkS")
		)
		(fp_line
			(start 2.393442 5.500116)
			(end 3.750056 5.500116)
			(stroke
				(width 0.1524)
				(type default)
			)
			(layer "F.SilkS")
		)
		(fp_line
			(start -2.393442 5.500116)
			(end -3.750056 5.500116)
			(stroke
				(width 0.1524)
				(type default)
			)
			(layer "F.SilkS")
		)
		(fp_line
			(start -3.750056 5.500116)
			(end -3.750056 -5.500116)
			(stroke
				(width 0.1524)
				(type default)
			)
			(layer "F.SilkS")
		)
		(fp_line
			(start -3.750056 -5.500116)
			(end -2.393442 -5.500116)
			(stroke
				(width 0.1524)
				(type default)
			)
			(layer "F.SilkS")
		)
		(fp_poly
			(pts
				(xy -4.04114 -3.352546) (xy -4.400296 -2.274824) (xy -5.118862 -2.993136)
			)
			(stroke
				(width 0)
				(type default)
			)
			(fill yes)
			(layer "F.SilkS")
		)
		(fp_line
			(start 3.750056 5.500116)
			(end 3.750056 -5.500116)
			(stroke
				(width 0.1)
				(type default)
			)
			(layer "F.Fab")
		)
		(fp_line
			(start 3.750056 -5.500116)
			(end -3.750056 -5.500116)
			(stroke
				(width 0.1)
				(type default)
			)
			(layer "F.Fab")
		)
		(fp_line
			(start -3.750056 5.500116)
			(end 3.750056 5.500116)
			(stroke
				(width 0.1)
				(type default)
			)
			(layer "F.Fab")
		)
		(fp_line
			(start -3.750056 -5.500116)
			(end -3.750056 5.500116)
			(stroke
				(width 0.1)
				(type default)
			)
			(layer "F.Fab")
		)
		(fp_poly
			(pts
				(xy -4.9276 -4.757928) (xy -4.9276 -3.741928) (xy -3.9116 -4.249928)
			)
			(stroke
				(width 0)
				(type default)
			)
			(fill yes)
			(layer "F.Fab")
		)
		(pad "1" smd rect
			(at 0 -4.249928 90)
			(size 2.413 4.5212)
			(layers "F.Cu" "F.Mask" "F.Paste")
			(net "SW_PVDDCR_CPU0_P1_SW5")
		)
		(pad "2" smd rect
			(at 0 -1.175004 90)
			(size 1.3716 4.5212)
			(layers "F.Cu" "F.Mask" "F.Paste")
			(net "IND_CPU0_P1_CPL6")
		)
		(pad "3" smd rect
			(at 0 1.175004 90)
			(size 1.3716 4.5212)
			(layers "F.Cu" "F.Mask" "F.Paste")
			(net "IND_CPU0_P1_CPL5")
		)
		(pad "4" smd rect
			(at 0 4.249928 90)
			(size 2.413 4.5212)
			(layers "F.Cu" "F.Mask" "F.Paste")
			(net "PVDDCR_CPU0_P1")
		)
	)
	(footprint ""
		(layer "F.Cu")
		(at 141.369542 -383.7432)
		(property "Reference" "R882"
			(at 0 0 0)
			(layer "F.SilkS")
			(hide yes)
			(effects
				(font
					(size 1.27 1.27)
				)
			)
		)
		(property "Value" ""
			(at 0 0 0)
			(layer "F.Fab")
			(effects
				(font
					(size 1.27 1.27)
				)
			)
		)
		(duplicate_pad_numbers_are_jumpers no)
		(fp_line
			(start -0.32512 -0.175006)
			(end 0.32512 -0.175006)
			(stroke
				(width 0.1)
				(type default)
			)
			(layer "F.Fab")
		)
		(fp_line
			(start -0.32512 0.175006)
			(end -0.32512 -0.175006)
			(stroke
				(width 0.1)
				(type default)
			)
			(layer "F.Fab")
		)
		(fp_line
			(start 0.32512 -0.175006)
			(end 0.32512 0.175006)
			(stroke
				(width 0.1)
				(type default)
			)
			(layer "F.Fab")
		)
		(fp_line
			(start 0.32512 0.175006)
			(end -0.32512 0.175006)
			(stroke
				(width 0.1)
				(type default)
			)
			(layer "F.Fab")
		)
		(pad "1" smd rect
			(at -0.2667 0)
			(size 0.3048 0.381)
			(layers "F.Cu" "F.Mask" "F.Paste")
			(net "P1V8_CPU1_RT_1D")
		)
		(pad "2" smd rect
			(at 0.2667 0 180)
			(size 0.3048 0.381)
			(layers "F.Cu" "F.Mask" "F.Paste")
			(net "TEST2_RT_CPU1_P2")
		)
	)
	(footprint ""
		(layer "F.Cu")
		(at 45.212 -170.815 180)
		(property "Reference" "R563"
			(at 0 0 180)
			(layer "F.SilkS")
			(hide yes)
			(effects
				(font
					(size 1.27 1.27)
				)
			)
		)
		(property "Value" ""
			(at 0 0 180)
			(layer "F.Fab")
			(effects
				(font
					(size 1.27 1.27)
				)
			)
		)
		(duplicate_pad_numbers_are_jumpers no)
		(fp_line
			(start 0.7874 0.4064)
			(end -0.7874 0.4064)
			(stroke
				(width 0.1524)
				(type default)
			)
			(layer "F.SilkS")
		)
		(fp_line
			(start 0.7874 -0.4064)
			(end 0.7874 0.4064)
			(stroke
				(width 0.1524)
				(type default)
			)
			(layer "F.SilkS")
		)
		(fp_line
			(start -0.7874 0.4064)
			(end -0.7874 -0.4064)
			(stroke
				(width 0.1524)
				(type default)
			)
			(layer "F.SilkS")
		)
		(fp_line
			(start -0.7874 -0.4064)
			(end 0.7874 -0.4064)
			(stroke
				(width 0.1524)
				(type default)
			)
			(layer "F.SilkS")
		)
		(fp_line
			(start 0.67945 0.3048)
			(end 0.120396 0.3048)
			(stroke
				(width 0.1)
				(type default)
			)
			(layer "F.Fab")
		)
		(fp_line
			(start 0.67945 -0.3048)
			(end 0.67945 0.3048)
			(stroke
				(width 0.1)
				(type default)
			)
			(layer "F.Fab")
		)
		(fp_line
			(start 0.12065 -0.2794)
			(end 0.12065 -0.3048)
			(stroke
				(width 0.1)
				(type default)
			)
			(layer "F.Fab")
		)
		(fp_line
			(start 0.12065 -0.3048)
			(end 0.67945 -0.3048)
			(stroke
				(width 0.1)
				(type default)
			)
			(layer "F.Fab")
		)
		(fp_line
			(start 0.120396 0.3048)
			(end 0.120396 0.2794)
			(stroke
				(width 0.1)
				(type default)
			)
			(layer "F.Fab")
		)
		(fp_line
			(start 0.120396 0.2794)
			(end -0.12065 0.2794)
			(stroke
				(width 0.1)
				(type default)
			)
			(layer "F.Fab")
		)
		(fp_line
			(start -0.12065 0.3048)
			(end -0.67945 0.3048)
			(stroke
				(width 0.1)
				(type default)
			)
			(layer "F.Fab")
		)
		(fp_line
			(start -0.12065 0.2794)
			(end -0.12065 0.3048)
			(stroke
				(width 0.1)
				(type default)
			)
			(layer "F.Fab")
		)
		(fp_line
			(start -0.12065 -0.2794)
			(end 0.12065 -0.2794)
			(stroke
				(width 0.1)
				(type default)
			)
			(layer "F.Fab")
		)
		(fp_line
			(start -0.12065 -0.305054)
			(end -0.12065 -0.2794)
			(stroke
				(width 0.1)
				(type default)
			)
			(layer "F.Fab")
		)
		(fp_line
			(start -0.67945 0.3048)
			(end -0.67945 -0.305054)
			(stroke
				(width 0.1)
				(type default)
			)
			(layer "F.Fab")
		)
		(fp_line
			(start -0.67945 -0.305054)
			(end -0.12065 -0.305054)
			(stroke
				(width 0.1)
				(type default)
			)
			(layer "F.Fab")
		)
		(pad "1" smd circle
			(at -0.40005 0 180)
			(size 0 0)
			(layers "F.Cu" "F.Mask" "F.Paste")
			(net "PVDD11_S3_P1")
		)
		(pad "2" smd circle
			(at 0.40005 0 180)
			(size 0 0)
			(layers "F.Cu" "F.Mask" "F.Paste")
			(net "I3C_0_SPD_DDRAF_CPU1_R_SCL")
		)
	)
	(footprint ""
		(layer "F.Cu")
		(at 232.517442 -315.82868 90)
		(property "Reference" "PC6532"
			(at -1.50368 3.729228 90)
			(unlocked yes)
			(layer "F.SilkS")
			(effects
				(font
					(size 0.7874 0.5842)
					(thickness 0.1524)
				)
				(justify left)
			)
		)
		(property "Value" ""
			(at 0 0 90)
			(layer "F.Fab")
			(effects
				(font
					(size 1.27 1.27)
				)
			)
		)
		(duplicate_pad_numbers_are_jumpers no)
		(fp_line
			(start 2.750058 -2.750058)
			(end -1.988058 -2.750058)
			(stroke
				(width 0.1524)
				(type default)
			)
			(layer "F.SilkS")
		)
		(fp_line
			(start -1.988058 -2.750058)
			(end -2.750058 -1.988058)
			(stroke
				(width 0.1524)
				(type default)
			)
			(layer "F.SilkS")
		)
		(fp_line
			(start -2.750058 -1.988058)
			(end -2.750058 -0.9398)
			(stroke
				(width 0.1524)
				(type default)
			)
			(layer "F.SilkS")
		)
		(fp_line
			(start 2.750058 -0.9398)
			(end 2.750058 -2.750058)
			(stroke
				(width 0.1524)
				(type default)
			)
			(layer "F.SilkS")
		)
		(fp_line
			(start -2.750058 0.9398)
			(end -2.750058 1.988058)
			(stroke
				(width 0.1524)
				(type default)
			)
			(layer "F.SilkS")
		)
		(fp_line
			(start -2.750058 1.988058)
			(end -1.988058 2.750058)
			(stroke
				(width 0.1524)
				(type default)
			)
			(layer "F.SilkS")
		)
		(fp_line
			(start 2.750058 2.750058)
			(end 2.750058 0.9398)
			(stroke
				(width 0.1524)
				(type default)
			)
			(layer "F.SilkS")
		)
		(fp_line
			(start -1.988058 2.750058)
			(end 2.750058 2.750058)
			(stroke
				(width 0.1524)
				(type default)
			)
			(layer "F.SilkS")
		)
		(fp_line
			(start 2.750058 -2.750058)
			(end -2.750058 -2.750058)
			(stroke
				(width 0.1)
				(type default)
			)
			(layer "F.Fab")
		)
		(fp_line
			(start -2.750058 -2.750058)
			(end -2.750058 2.750058)
			(stroke
				(width 0.1)
				(type default)
			)
			(layer "F.Fab")
		)
		(fp_line
			(start 2.750058 2.750058)
			(end 2.750058 -2.750058)
			(stroke
				(width 0.1)
				(type default)
			)
			(layer "F.Fab")
		)
		(fp_line
			(start -2.750058 2.750058)
			(end 2.750058 2.750058)
			(stroke
				(width 0.1)
				(type default)
			)
			(layer "F.Fab")
		)
		(pad "1" smd rect
			(at -2.199894 0 180)
			(size 1.6002 3.0226)
			(layers "F.Cu" "F.Mask" "F.Paste")
			(net "P1V8_CPU1_RT_1D")
		)
		(pad "2" smd rect
			(at 2.199894 0 180)
			(size 1.6002 3.0226)
			(layers "F.Cu" "F.Mask" "F.Paste")
			(net "GND")
		)
	)
	(footprint ""
		(layer "F.Cu")
		(at 102.961948 -381.7874 180)
		(property "Reference" "R1376"
			(at 0 0 180)
			(layer "F.SilkS")
			(hide yes)
			(effects
				(font
					(size 1.27 1.27)
				)
			)
		)
		(property "Value" ""
			(at 0 0 180)
			(layer "F.Fab")
			(effects
				(font
					(size 1.27 1.27)
				)
			)
		)
		(duplicate_pad_numbers_are_jumpers no)
		(fp_line
			(start 0.32512 0.175006)
			(end -0.32512 0.175006)
			(stroke
				(width 0.1)
				(type default)
			)
			(layer "F.Fab")
		)
		(fp_line
			(start 0.32512 -0.175006)
			(end 0.32512 0.175006)
			(stroke
				(width 0.1)
				(type default)
			)
			(layer "F.Fab")
		)
		(fp_line
			(start -0.32512 0.175006)
			(end -0.32512 -0.175006)
			(stroke
				(width 0.1)
				(type default)
			)
			(layer "F.Fab")
		)
		(fp_line
			(start -0.32512 -0.175006)
			(end 0.32512 -0.175006)
			(stroke
				(width 0.1)
				(type default)
			)
			(layer "F.Fab")
		)
		(pad "1" smd rect
			(at -0.2667 0 180)
			(size 0.3048 0.381)
			(layers "F.Cu" "F.Mask" "F.Paste")
			(net "CLKREQ_RT_CPU1_P1_N")
		)
		(pad "2" smd rect
			(at 0.2667 0)
			(size 0.3048 0.381)
			(layers "F.Cu" "F.Mask" "F.Paste")
			(net "GND")
		)
	)
	(footprint ""
		(layer "F.Cu")
		(at 275.539962 -337.399122)
		(property "Reference" "PL20"
			(at -1.854962 -15.888208 0)
			(unlocked yes)
			(layer "F.SilkS")
			(effects
				(font
					(size 0.7874 0.5842)
					(thickness 0.1524)
				)
				(justify left)
			)
		)
		(property "Value" ""
			(at 0 0 0)
			(layer "F.Fab")
			(effects
				(font
					(size 1.27 1.27)
				)
			)
		)
		(duplicate_pad_numbers_are_jumpers no)
		(fp_line
			(start -3.750056 -5.500116)
			(end -2.393442 -5.500116)
			(stroke
				(width 0.1524)
				(type default)
			)
			(layer "F.SilkS")
		)
		(fp_line
			(start -3.750056 5.500116)
			(end -3.750056 -5.500116)
			(stroke
				(width 0.1524)
				(type default)
			)
			(layer "F.SilkS")
		)
		(fp_line
			(start -2.393442 5.500116)
			(end -3.750056 5.500116)
			(stroke
				(width 0.1524)
				(type default)
			)
			(layer "F.SilkS")
		)
		(fp_line
			(start 2.393442 5.500116)
			(end 3.750056 5.500116)
			(stroke
				(width 0.1524)
				(type default)
			)
			(layer "F.SilkS")
		)
		(fp_line
			(start 3.750056 -5.500116)
			(end 2.393442 -5.500116)
			(stroke
				(width 0.1524)
				(type default)
			)
			(layer "F.SilkS")
		)
		(fp_line
			(start 3.750056 5.500116)
			(end 3.750056 -5.500116)
			(stroke
				(width 0.1524)
				(type default)
			)
			(layer "F.SilkS")
		)
		(fp_poly
			(pts
				(xy -3.965448 -5.22478) (xy -4.42341 -5.377434) (xy -4.118102 -5.682742)
			)
			(stroke
				(width 0)
				(type default)
			)
			(fill yes)
			(layer "F.SilkS")
		)
		(fp_line
			(start -3.750056 -5.500116)
			(end -3.750056 5.500116)
			(stroke
				(width 0.1)
				(type default)
			)
			(layer "F.Fab")
		)
		(fp_line
			(start -3.750056 5.500116)
			(end 3.750056 5.500116)
			(stroke
				(width 0.1)
				(type default)
			)
			(layer "F.Fab")
		)
		(fp_line
			(start 3.750056 -5.500116)
			(end -3.750056 -5.500116)
			(stroke
				(width 0.1)
				(type default)
			)
			(layer "F.Fab")
		)
		(fp_line
			(start 3.750056 5.500116)
			(end 3.750056 -5.500116)
			(stroke
				(width 0.1)
				(type default)
			)
			(layer "F.Fab")
		)
		(fp_poly
			(pts
				(xy -4.9276 -4.757928) (xy -4.9276 -3.741928) (xy -3.9116 -4.249928)
			)
			(stroke
				(width 0)
				(type default)
			)
			(fill yes)
			(layer "F.Fab")
		)
		(pad "1" smd rect
			(at 0 -4.249928 270)
			(size 2.413 4.5212)
			(layers "F.Cu" "F.Mask" "F.Paste")
			(net "SW_PVDDIO_P0_SW4")
		)
		(pad "2" smd rect
			(at 0 -1.175004 270)
			(size 1.3716 4.5212)
			(layers "F.Cu" "F.Mask" "F.Paste")
			(net "IND_PVDDIO_P0_CPL0")
		)
		(pad "3" smd rect
			(at 0 1.175004 270)
			(size 1.3716 4.5212)
			(layers "F.Cu" "F.Mask" "F.Paste")
			(net "IND_PVDDIO_P0_CPL4")
		)
		(pad "4" smd rect
			(at 0 4.249928 270)
			(size 2.413 4.5212)
			(layers "F.Cu" "F.Mask" "F.Paste")
			(net "PVDDIO_P0")
		)
	)
	(footprint ""
		(layer "F.Cu")
		(at 171.196 -107.152948 180)
		(property "Reference" "R170"
			(at 0 0 180)
			(layer "F.SilkS")
			(hide yes)
			(effects
				(font
					(size 1.27 1.27)
				)
			)
		)
		(property "Value" ""
			(at 0 0 180)
			(layer "F.Fab")
			(effects
				(font
					(size 1.27 1.27)
				)
			)
		)
		(duplicate_pad_numbers_are_jumpers no)
		(fp_line
			(start 0.7874 0.4064)
			(end -0.7874 0.4064)
			(stroke
				(width 0.1524)
				(type default)
			)
			(layer "F.SilkS")
		)
		(fp_line
			(start 0.7874 -0.4064)
			(end 0.7874 0.4064)
			(stroke
				(width 0.1524)
				(type default)
			)
			(layer "F.SilkS")
		)
		(fp_line
			(start -0.7874 0.4064)
			(end -0.7874 -0.4064)
			(stroke
				(width 0.1524)
				(type default)
			)
			(layer "F.SilkS")
		)
		(fp_line
			(start -0.7874 -0.4064)
			(end 0.7874 -0.4064)
			(stroke
				(width 0.1524)
				(type default)
			)
			(layer "F.SilkS")
		)
		(fp_line
			(start 0.67945 0.3048)
			(end 0.120396 0.3048)
			(stroke
				(width 0.1)
				(type default)
			)
			(layer "F.Fab")
		)
		(fp_line
			(start 0.67945 -0.3048)
			(end 0.67945 0.3048)
			(stroke
				(width 0.1)
				(type default)
			)
			(layer "F.Fab")
		)
		(fp_line
			(start 0.12065 -0.2794)
			(end 0.12065 -0.3048)
			(stroke
				(width 0.1)
				(type default)
			)
			(layer "F.Fab")
		)
		(fp_line
			(start 0.12065 -0.3048)
			(end 0.67945 -0.3048)
			(stroke
				(width 0.1)
				(type default)
			)
			(layer "F.Fab")
		)
		(fp_line
			(start 0.120396 0.3048)
			(end 0.120396 0.2794)
			(stroke
				(width 0.1)
				(type default)
			)
			(layer "F.Fab")
		)
		(fp_line
			(start 0.120396 0.2794)
			(end -0.12065 0.2794)
			(stroke
				(width 0.1)
				(type default)
			)
			(layer "F.Fab")
		)
		(fp_line
			(start -0.12065 0.3048)
			(end -0.67945 0.3048)
			(stroke
				(width 0.1)
				(type default)
			)
			(layer "F.Fab")
		)
		(fp_line
			(start -0.12065 0.2794)
			(end -0.12065 0.3048)
			(stroke
				(width 0.1)
				(type default)
			)
			(layer "F.Fab")
		)
		(fp_line
			(start -0.12065 -0.2794)
			(end 0.12065 -0.2794)
			(stroke
				(width 0.1)
				(type default)
			)
			(layer "F.Fab")
		)
		(fp_line
			(start -0.12065 -0.305054)
			(end -0.12065 -0.2794)
			(stroke
				(width 0.1)
				(type default)
			)
			(layer "F.Fab")
		)
		(fp_line
			(start -0.67945 0.3048)
			(end -0.67945 -0.305054)
			(stroke
				(width 0.1)
				(type default)
			)
			(layer "F.Fab")
		)
		(fp_line
			(start -0.67945 -0.305054)
			(end -0.12065 -0.305054)
			(stroke
				(width 0.1)
				(type default)
			)
			(layer "F.Fab")
		)
		(pad "1" smd circle
			(at -0.40005 0 180)
			(size 0 0)
			(layers "F.Cu" "F.Mask" "F.Paste")
			(net "FM_I3C_CPU1_MUX0_R_SEL")
		)
		(pad "2" smd circle
			(at 0.40005 0 180)
			(size 0 0)
			(layers "F.Cu" "F.Mask" "F.Paste")
			(net "FM_I3C_CPU1_MUX0_SEL")
		)
	)
)
